# SCM (Grand Teton) — schematic netlist excerpt (pin names and nets, part order shuffled) for the footprints in the layout excerpt that follows; sources: Cadence DE-HDL packaged netlist, KiCad conversion of 12092022_DA0F0TMDCD0_F0T_Management_Board_D_brd_V3_OCP.brd

U16  74LVC1G07GW  EMPTY  pkg SOT353_Q  page 50
  NC  = NC_U16_P1
  A  = REAR_AC_PWR_BTN_N
  GND  = GND
  Y  = AC_PWR_BTN_R1_N
  VCC  = P3V3_AUX

R316  Q_RES  0 5% CHIP  pkg 0402LF  page 15 : A = BMC_PWR_LED ; B = PWR_LED

(kicad_pcb
	(version 20260206)
	(generator "pcbnew")
	(generator_version "10.0")
	(general
		(thickness 1.6)
		(legacy_teardrops no)
	)
	(paper "A4")
	(title_block
		(title "12092022_DA0F0TMDCD0_F0T_Management_Board_D_brd_V3_OCP.brd")
		(comment 1 "Grand Teton / footprints 125-126 of 1440")
	)
	(layers
		(0 "F.Cu" signal "TOP")
		(4 "In1.Cu" signal "GND")
		(6 "In2.Cu" signal "IN1")
		(8 "In3.Cu" signal "GND1")
		(10 "In4.Cu" signal "IN2")
		(12 "In5.Cu" signal "VCC")
		(14 "In6.Cu" signal "VCC1")
		(16 "In7.Cu" signal "IN3")
		(18 "In8.Cu" signal "GND2")
		(20 "In9.Cu" signal "IN4")
		(22 "In10.Cu" signal "GND3")
		(2 "B.Cu" signal "BOTTOM")
		(9 "F.Adhes" user "F.Adhesive")
		(11 "B.Adhes" user "B.Adhesive")
		(13 "F.Paste" user "Package Geometry/Pastemask Top")
		(15 "B.Paste" user "Package Geometry/Pastemask Bottom")
		(5 "F.SilkS" user "Ref Des/Silkscreen Top")
		(7 "B.SilkS" user "Ref Des/Silkscreen Bottom")
		(1 "F.Mask" user "Board Geometry/Soldermask Top")
		(3 "B.Mask" user "Board Geometry/Soldermask Bottom")
		(17 "Dwgs.User" user "User.Drawings")
		(19 "Cmts.User" user "User.Comments")
		(21 "Eco1.User" user "User.Eco1")
		(23 "Eco2.User" user "User.Eco2")
		(25 "Edge.Cuts" user "Board Geometry/Outline")
		(27 "Margin" user)
		(31 "F.CrtYd" user "Package Geometry/Place Bound Top")
		(29 "B.CrtYd" user "Package Geometry/Place Bound Bottom")
		(35 "F.Fab" user "Ref Des/Assembly Top")
		(33 "B.Fab" user "Ref Des/Assembly Bottom")
	)
	(footprint ""
		(layer "F.Cu")
		(at 73.533 -13.843)
		(property "Reference" "U16"
			(at 0.7874 -1.80213 0)
			(unlocked yes)
			(layer "F.SilkS")
			(effects
				(font
					(size 0.7874 0.5842)
					(thickness 0.1524)
				)
				(justify left)
			)
		)
		(property "Value" ""
			(at 0 0 0)
			(layer "F.Fab")
			(effects
				(font
					(size 1.27 1.27)
				)
			)
		)
		(duplicate_pad_numbers_are_jumpers no)
		(fp_line
			(start -1.4986 -1.100074)
			(end 1.4986 -1.100074)
			(stroke
				(width 0.1524)
				(type default)
			)
			(layer "F.SilkS")
		)
		(fp_line
			(start -1.4986 1.100074)
			(end -1.4986 -1.100074)
			(stroke
				(width 0.1524)
				(type default)
			)
			(layer "F.SilkS")
		)
		(fp_line
			(start 1.4986 -1.100074)
			(end 1.4986 1.100074)
			(stroke
				(width 0.1524)
				(type default)
			)
			(layer "F.SilkS")
		)
		(fp_line
			(start 1.4986 1.100074)
			(end -1.4986 1.100074)
			(stroke
				(width 0.1524)
				(type default)
			)
			(layer "F.SilkS")
		)
		(fp_poly
			(pts
				(xy -1.90881 -1.728724) (xy -1.28397 -1.728724) (xy -1.612138 -1.175004)
			)
			(stroke
				(width 0)
				(type default)
			)
			(fill yes)
			(layer "F.SilkS")
		)
		(fp_line
			(start -0.67437 -1.100074)
			(end 0.67437 -1.100074)
			(stroke
				(width 0.1)
				(type default)
			)
			(layer "F.Fab")
		)
		(fp_line
			(start -0.67437 1.100074)
			(end -0.67437 -1.100074)
			(stroke
				(width 0.1)
				(type default)
			)
			(layer "F.Fab")
		)
		(fp_line
			(start 0.67437 -1.100074)
			(end 0.67437 1.100074)
			(stroke
				(width 0.1)
				(type default)
			)
			(layer "F.Fab")
		)
		(fp_line
			(start 0.67437 1.100074)
			(end -0.67437 1.100074)
			(stroke
				(width 0.1)
				(type default)
			)
			(layer "F.Fab")
		)
		(fp_poly
			(pts
				(xy -2.20472 -0.338328) (xy -2.20472 -0.963168) (xy -1.651 -0.635)
			)
			(stroke
				(width 0)
				(type default)
			)
			(fill yes)
			(layer "F.Fab")
		)
		(pad "1" smd rect
			(at -0.889 -0.649986)
			(size 1.016 0.381)
			(layers "F.Cu" "F.Mask" "F.Paste")
			(net "NC_U16_P1")
		)
		(pad "2" smd rect
			(at -0.889 0)
			(size 1.016 0.381)
			(layers "F.Cu" "F.Mask" "F.Paste")
			(net "REAR_AC_PWR_BTN_N")
		)
		(pad "3" smd rect
			(at -0.889 0.649986)
			(size 1.016 0.381)
			(layers "F.Cu" "F.Mask" "F.Paste")
			(net "GND")
		)
		(pad "4" smd rect
			(at 0.889 0.649986)
			(size 1.016 0.381)
			(layers "F.Cu" "F.Mask" "F.Paste")
			(net "AC_PWR_BTN_R1_N")
		)
		(pad "5" smd rect
			(at 0.889 -0.649986)
			(size 1.016 0.381)
			(layers "F.Cu" "F.Mask" "F.Paste")
			(net "P3V3_AUX")
		)
	)
	(footprint ""
		(layer "F.Cu")
		(at 34.417 -51.181 180)
		(property "Reference" "R316"
			(at 0 0 180)
			(layer "F.SilkS")
			(hide yes)
			(effects
				(font
					(size 1.27 1.27)
				)
			)
		)
		(property "Value" ""
			(at 0 0 180)
			(layer "F.Fab")
			(effects
				(font
					(size 1.27 1.27)
				)
			)
		)
		(duplicate_pad_numbers_are_jumpers no)
		(fp_line
			(start 0.7874 0.4064)
			(end -0.7874 0.4064)
			(stroke
				(width 0.1524)
				(type default)
			)
			(layer "F.SilkS")
		)
		(fp_line
			(start 0.7874 -0.4064)
			(end 0.7874 0.4064)
			(stroke
				(width 0.1524)
				(type default)
			)
			(layer "F.SilkS")
		)
		(fp_line
			(start -0.7874 0.4064)
			(end -0.7874 -0.4064)
			(stroke
				(width 0.1524)
				(type default)
			)
			(layer "F.SilkS")
		)
		(fp_line
			(start -0.7874 -0.4064)
			(end 0.7874 -0.4064)
			(stroke
				(width 0.1524)
				(type default)
			)
			(layer "F.SilkS")
		)
		(fp_line
			(start 0.67945 0.3048)
			(end 0.120396 0.3048)
			(stroke
				(width 0.1)
				(type default)
			)
			(layer "F.Fab")
		)
		(fp_line
			(start 0.67945 -0.3048)
			(end 0.67945 0.3048)
			(stroke
				(width 0.1)
				(type default)
			)
			(layer "F.Fab")
		)
		(fp_line
			(start 0.12065 -0.2794)
			(end 0.12065 -0.3048)
			(stroke
				(width 0.1)
				(type default)
			)
			(layer "F.Fab")
		)
		(fp_line
			(start 0.12065 -0.3048)
			(end 0.67945 -0.3048)
			(stroke
				(width 0.1)
				(type default)
			)
			(layer "F.Fab")
		)
		(fp_line
			(start 0.120396 0.3048)
			(end 0.120396 0.2794)
			(stroke
				(width 0.1)
				(type default)
			)
			(layer "F.Fab")
		)
		(fp_line
			(start 0.120396 0.2794)
			(end -0.12065 0.2794)
			(stroke
				(width 0.1)
				(type default)
			)
			(layer "F.Fab")
		)
		(fp_line
			(start -0.12065 0.3048)
			(end -0.67945 0.3048)
			(stroke
				(width 0.1)
				(type default)
			)
			(layer "F.Fab")
		)
		(fp_line
			(start -0.12065 0.2794)
			(end -0.12065 0.3048)
			(stroke
				(width 0.1)
				(type default)
			)
			(layer "F.Fab")
		)
		(fp_line
			(start -0.12065 -0.2794)
			(end 0.12065 -0.2794)
			(stroke
				(width 0.1)
				(type default)
			)
			(layer "F.Fab")
		)
		(fp_line
			(start -0.12065 -0.305054)
			(end -0.12065 -0.2794)
			(stroke
				(width 0.1)
				(type default)
			)
			(layer "F.Fab")
		)
		(fp_line
			(start -0.67945 0.3048)
			(end -0.67945 -0.305054)
			(stroke
				(width 0.1)
				(type default)
			)
			(layer "F.Fab")
		)
		(fp_line
			(start -0.67945 -0.305054)
			(end -0.12065 -0.305054)
			(stroke
				(width 0.1)
				(type default)
			)
			(layer "F.Fab")
		)
		(pad "1" smd circle
			(at -0.40005 0 180)
			(size 0 0)
			(layers "F.Cu" "F.Mask" "F.Paste")
			(net "BMC_PWR_LED")
		)
		(pad "2" smd circle
			(at 0.40005 0 180)
			(size 0 0)
			(layers "F.Cu" "F.Mask" "F.Paste")
			(net "PWR_LED")
		)
	)
)
